# Stackup_F0T_FIO_4L_1p6mm_IT-170GT_RTF_Rev0p1_20211105.xls — Vendor Stackup (pcb-stackup)
| STACKUP |  |  |  | Target Z (ohms) - MicroStrip |  |  |  |  |  |  |  | 50 |  |  | Breakout | 85 |  |  |  |  | Breakout |  |
|  |  |  |  | Target Z (ohms) - StripLine |  |  |  |  |  |  |  | 50 |  |  |  | 85 |  |  |  |  |  |  |
|  |  |  |  | Z tolerance |  |  |  |  |  |  |  | 0.1 |  |  |  | 0.1 |  |  |  |  |  |  |
|  |  |  |  | Z Type |  |  |  |  |  |  |  | Single |  |  | Single | Differential |  |  |  |  | Differential |  |
| Layer# | Material | Description |  | Copper Weight (oz) | Thickness (mil) | Tolerance (mil) | Glass Fabric | Er | Vendor Thickness (mil) | Vendor Glass Fabric | Vendor Er | Width | Vendor Width | Vendor Impedance | Width | Width | Space | Vendor Width | Vendor Space | Vendor Impedance | Width | Space |
|  |  |  | Soldermask |  | 0.6 |  |  | 3.8 |  |  |  |  |  |  |  |  |  |  |  |  |  |  |
| 1 |  |  | TOP | 0.5+plating | 1.95 |  |  |  |  |  |  | 7.4 |  |  | 4 | 5.8 | 4.2 |  |  |  | 3.9 | 4 |
|  | IT-170GT |  | PP |  | 4 | ±0.709 | 2116x1 | 3.87 |  |  |  |  |  |  |  |  |  |  |  |  |  |  |
| 2 |  |  | GND | 1 (RTF) | 1.3 |  |  |  |  |  |  |  |  |  |  |  |  |  |  |  |  |  |
|  | IT-170GT |  | CORE |  | 47.3 | ±5.12 | Vendor Define | 4.17 |  |  |  |  |  |  |  |  |  |  |  |  |  |  |
| 3 |  |  | GND1 | 1 (RTF) | 1.3 |  |  |  |  |  |  |  |  |  |  |  |  |  |  |  |  |  |
|  | IT-170GT |  | PP |  | 4 | ±0.709 | 2116x1 | 3.87 |  |  |  |  |  |  |  |  |  |  |  |  |  |  |
| 4 |  |  | BOTTOM | 0.5+plating | 1.95 |  |  |  |  |  |  | 7.4 |  |  | 4 | 5.8 | 4.2 |  |  |  | 3.9 | 4 |
|  |  |  | Soldermask |  | 0.6 |  |  | 3.8 |  |  |  |  |  |  |  |  |  |  |  |  |  |  |
|  |  |  |  | Total | 63 | ±10% |  |  | 0 |  |  |  |  |  |  |  |  |  |  |  |  |  |
